# T6G (Grand Teton) — schematic netlist excerpt (pin names and nets, part order shuffled) for the footprints in the layout excerpt that follows; sources: Cadence DE-HDL packaged netlist, KiCad conversion of 04192023_DAF0TMB3IC0_F0TG_MB_C_brd_V02_OCP.brd

R8013  Q_RES  0 5% EMPTY  pkg 0402LF  page 143 : A = OCP_SFF_PRSNT01_R_N ; B = OCP_SFF_PRSNT01_R1_N
C1091  Q_CAP  0.1UF 25V 10% X7R  pkg 0402  page 258 : A = P1V8_CPU1_RT_1D_ADC_TIC ; B = GND
R846  Q_RES  4.7K 5% CHIP  pkg 0201LF  page 185 : A = RT_ROM_SMB_MUX_ADDR1 ; B = GND

(kicad_pcb
	(version 20260206)
	(generator "pcbnew")
	(generator_version "10.0")
	(general
		(thickness 1.6)
		(legacy_teardrops no)
	)
	(paper "A4")
	(title_block
		(title "04192023_DAF0TMB3IC0_F0TG_MB_C_brd_V02_OCP.brd")
		(comment 1 "Grand Teton / footprints 6986-6988 of 8354")
	)
	(layers
		(0 "F.Cu" signal "TOP")
		(4 "In1.Cu" signal "GND")
		(6 "In2.Cu" signal "IN1")
		(8 "In3.Cu" signal "GND1")
		(10 "In4.Cu" signal "IN2")
		(12 "In5.Cu" signal "GND2")
		(14 "In6.Cu" signal "IN3")
		(16 "In7.Cu" signal "GND3")
		(18 "In8.Cu" signal "VCC")
		(20 "In9.Cu" signal "VCC1")
		(22 "In10.Cu" signal "GND4")
		(24 "In11.Cu" signal "IN4")
		(26 "In12.Cu" signal "GND5")
		(28 "In13.Cu" signal "IN5")
		(30 "In14.Cu" signal "GND6")
		(32 "In15.Cu" signal "IN6")
		(34 "In16.Cu" signal "GND7")
		(2 "B.Cu" signal "BOTTOM")
		(9 "F.Adhes" user "F.Adhesive")
		(11 "B.Adhes" user "B.Adhesive")
		(13 "F.Paste" user "Package Geometry/Pastemask Top")
		(15 "B.Paste" user "Package Geometry/Pastemask Bottom")
		(5 "F.SilkS" user "Ref Des/Silkscreen Top")
		(7 "B.SilkS" user "Ref Des/Silkscreen Bottom")
		(1 "F.Mask" user "Board Geometry/Soldermask Top")
		(3 "B.Mask" user "Board Geometry/Soldermask Bottom")
		(17 "Dwgs.User" user "User.Drawings")
		(19 "Cmts.User" user "User.Comments")
		(21 "Eco1.User" user "User.Eco1")
		(23 "Eco2.User" user "User.Eco2")
		(25 "Edge.Cuts" user "Board Geometry/Outline")
		(27 "Margin" user)
		(31 "F.CrtYd" user "Package Geometry/Place Bound Top")
		(29 "B.CrtYd" user "Package Geometry/Place Bound Bottom")
		(35 "F.Fab" user "Ref Des/Assembly Top")
		(33 "B.Fab" user "Ref Des/Assembly Bottom")
	)
	(footprint ""
		(layer "B.Cu")
		(at 239.141 -331.47)
		(property "Reference" "R846"
			(at 0 0 0)
			(layer "B.SilkS")
			(hide yes)
			(effects
				(font
					(size 1.27 1.27)
				)
				(justify mirror)
			)
		)
		(property "Value" ""
			(at 0 0 0)
			(layer "B.Fab")
			(effects
				(font
					(size 1.27 1.27)
				)
				(justify mirror)
			)
		)
		(duplicate_pad_numbers_are_jumpers no)
		(fp_line
			(start -0.32512 -0.175006)
			(end -0.32512 0.175006)
			(stroke
				(width 0.1)
				(type default)
			)
			(layer "B.Fab")
		)
		(fp_line
			(start -0.32512 0.175006)
			(end 0.32512 0.175006)
			(stroke
				(width 0.1)
				(type default)
			)
			(layer "B.Fab")
		)
		(fp_line
			(start 0.32512 -0.175006)
			(end -0.32512 -0.175006)
			(stroke
				(width 0.1)
				(type default)
			)
			(layer "B.Fab")
		)
		(fp_line
			(start 0.32512 0.175006)
			(end 0.32512 -0.175006)
			(stroke
				(width 0.1)
				(type default)
			)
			(layer "B.Fab")
		)
		(pad "1" smd rect
			(at 0.2667 0 180)
			(size 0.3048 0.381)
			(layers "B.Cu" "B.Mask" "B.Paste")
			(net "RT_ROM_SMB_MUX_ADDR1")
		)
		(pad "2" smd rect
			(at -0.2667 0)
			(size 0.3048 0.381)
			(layers "B.Cu" "B.Mask" "B.Paste")
			(net "GND")
		)
	)
	(footprint ""
		(layer "B.Cu")
		(at 228.485192 -326.49668 180)
		(property "Reference" "C1091"
			(at 0 0 0)
			(layer "B.SilkS")
			(hide yes)
			(effects
				(font
					(size 1.27 1.27)
				)
				(justify mirror)
			)
		)
		(property "Value" ""
			(at 0 0 0)
			(layer "B.Fab")
			(effects
				(font
					(size 1.27 1.27)
				)
				(justify mirror)
			)
		)
		(duplicate_pad_numbers_are_jumpers no)
		(fp_line
			(start 0.7874 0.4064)
			(end 0.7874 -0.4064)
			(stroke
				(width 0.1524)
				(type default)
			)
			(layer "B.SilkS")
		)
		(fp_line
			(start 0.7874 -0.4064)
			(end -0.7874 -0.4064)
			(stroke
				(width 0.1524)
				(type default)
			)
			(layer "B.SilkS")
		)
		(fp_line
			(start -0.7874 0.4064)
			(end 0.7874 0.4064)
			(stroke
				(width 0.1524)
				(type default)
			)
			(layer "B.SilkS")
		)
		(fp_line
			(start -0.7874 -0.4064)
			(end -0.7874 0.4064)
			(stroke
				(width 0.1524)
				(type default)
			)
			(layer "B.SilkS")
		)
		(fp_line
			(start 0.67945 0.3048)
			(end 0.67945 -0.305054)
			(stroke
				(width 0.1)
				(type default)
			)
			(layer "B.Fab")
		)
		(fp_line
			(start 0.67945 -0.305054)
			(end 0.12065 -0.305054)
			(stroke
				(width 0.1)
				(type default)
			)
			(layer "B.Fab")
		)
		(fp_line
			(start 0.12065 0.3048)
			(end 0.67945 0.3048)
			(stroke
				(width 0.1)
				(type default)
			)
			(layer "B.Fab")
		)
		(fp_line
			(start 0.12065 0.2794)
			(end 0.12065 0.3048)
			(stroke
				(width 0.1)
				(type default)
			)
			(layer "B.Fab")
		)
		(fp_line
			(start 0.12065 -0.2794)
			(end -0.12065 -0.2794)
			(stroke
				(width 0.1)
				(type default)
			)
			(layer "B.Fab")
		)
		(fp_line
			(start 0.12065 -0.305054)
			(end 0.12065 -0.2794)
			(stroke
				(width 0.1)
				(type default)
			)
			(layer "B.Fab")
		)
		(fp_line
			(start -0.120396 0.3048)
			(end -0.120396 0.2794)
			(stroke
				(width 0.1)
				(type default)
			)
			(layer "B.Fab")
		)
		(fp_line
			(start -0.120396 0.2794)
			(end 0.12065 0.2794)
			(stroke
				(width 0.1)
				(type default)
			)
			(layer "B.Fab")
		)
		(fp_line
			(start -0.12065 -0.2794)
			(end -0.12065 -0.3048)
			(stroke
				(width 0.1)
				(type default)
			)
			(layer "B.Fab")
		)
		(fp_line
			(start -0.12065 -0.3048)
			(end -0.67945 -0.3048)
			(stroke
				(width 0.1)
				(type default)
			)
			(layer "B.Fab")
		)
		(fp_line
			(start -0.67945 0.3048)
			(end -0.120396 0.3048)
			(stroke
				(width 0.1)
				(type default)
			)
			(layer "B.Fab")
		)
		(fp_line
			(start -0.67945 -0.3048)
			(end -0.67945 0.3048)
			(stroke
				(width 0.1)
				(type default)
			)
			(layer "B.Fab")
		)
		(pad "1" smd circle
			(at 0.40005 0)
			(size 0 0)
			(layers "B.Cu" "B.Mask" "B.Paste")
			(net "P1V8_CPU1_RT_1D_ADC_TIC")
		)
		(pad "2" smd circle
			(at -0.40005 0)
			(size 0 0)
			(layers "B.Cu" "B.Mask" "B.Paste")
			(net "GND")
		)
	)
	(footprint ""
		(layer "B.Cu")
		(at 11.049 -81.153 90)
		(property "Reference" "R8013"
			(at 0 0 90)
			(layer "B.SilkS")
			(hide yes)
			(effects
				(font
					(size 1.27 1.27)
				)
				(justify mirror)
			)
		)
		(property "Value" ""
			(at 0 0 90)
			(layer "B.Fab")
			(effects
				(font
					(size 1.27 1.27)
				)
				(justify mirror)
			)
		)
		(duplicate_pad_numbers_are_jumpers no)
		(fp_line
			(start 0.7874 -0.4064)
			(end -0.7874 -0.4064)
			(stroke
				(width 0.1524)
				(type default)
			)
			(layer "B.SilkS")
		)
		(fp_line
			(start -0.7874 -0.4064)
			(end -0.7874 0.4064)
			(stroke
				(width 0.1524)
				(type default)
			)
			(layer "B.SilkS")
		)
		(fp_line
			(start 0.7874 0.4064)
			(end 0.7874 -0.4064)
			(stroke
				(width 0.1524)
				(type default)
			)
			(layer "B.SilkS")
		)
		(fp_line
			(start -0.7874 0.4064)
			(end 0.7874 0.4064)
			(stroke
				(width 0.1524)
				(type default)
			)
			(layer "B.SilkS")
		)
		(fp_line
			(start 0.67945 -0.305054)
			(end 0.12065 -0.305054)
			(stroke
				(width 0.1)
				(type default)
			)
			(layer "B.Fab")
		)
		(fp_line
			(start 0.12065 -0.305054)
			(end 0.12065 -0.2794)
			(stroke
				(width 0.1)
				(type default)
			)
			(layer "B.Fab")
		)
		(fp_line
			(start -0.12065 -0.3048)
			(end -0.67945 -0.3048)
			(stroke
				(width 0.1)
				(type default)
			)
			(layer "B.Fab")
		)
		(fp_line
			(start -0.67945 -0.3048)
			(end -0.67945 0.3048)
			(stroke
				(width 0.1)
				(type default)
			)
			(layer "B.Fab")
		)
		(fp_line
			(start 0.12065 -0.2794)
			(end -0.12065 -0.2794)
			(stroke
				(width 0.1)
				(type default)
			)
			(layer "B.Fab")
		)
		(fp_line
			(start -0.12065 -0.2794)
			(end -0.12065 -0.3048)
			(stroke
				(width 0.1)
				(type default)
			)
			(layer "B.Fab")
		)
		(fp_line
			(start 0.12065 0.2794)
			(end 0.12065 0.3048)
			(stroke
				(width 0.1)
				(type default)
			)
			(layer "B.Fab")
		)
		(fp_line
			(start -0.120396 0.2794)
			(end 0.12065 0.2794)
			(stroke
				(width 0.1)
				(type default)
			)
			(layer "B.Fab")
		)
		(fp_line
			(start 0.67945 0.3048)
			(end 0.67945 -0.305054)
			(stroke
				(width 0.1)
				(type default)
			)
			(layer "B.Fab")
		)
		(fp_line
			(start 0.12065 0.3048)
			(end 0.67945 0.3048)
			(stroke
				(width 0.1)
				(type default)
			)
			(layer "B.Fab")
		)
		(fp_line
			(start -0.120396 0.3048)
			(end -0.120396 0.2794)
			(stroke
				(width 0.1)
				(type default)
			)
			(layer "B.Fab")
		)
		(fp_line
			(start -0.67945 0.3048)
			(end -0.120396 0.3048)
			(stroke
				(width 0.1)
				(type default)
			)
			(layer "B.Fab")
		)
		(pad "1" smd circle
			(at 0.40005 0 270)
			(size 0 0)
			(layers "B.Cu" "B.Mask" "B.Paste")
			(net "OCP_SFF_PRSNT01_R_N")
		)
		(pad "2" smd circle
			(at -0.40005 0 270)
			(size 0 0)
			(layers "B.Cu" "B.Mask" "B.Paste")
			(net "OCP_SFF_PRSNT01_R1_N")
		)
	)
)
